(kicad_pcb
	(version 20260206)
	(generator "pcbnew")
	(generator_version "10.0")
	(general
		(thickness 1.6)
		(legacy_teardrops no)
	)
	(paper "A4")
	(title_block
		(title "01162023_DA0F0TEBIF0_F0T_Expander_BD_F_brd_V02_OCP.brd")
		(comment 1 "Grand Teton / footprints 3476-3480 of 9728")
	)
	(layers
		(0 "F.Cu" signal "TOP")
		(4 "In1.Cu" signal "GND")
		(6 "In2.Cu" signal "VCC")
		(8 "In3.Cu" signal "VCC1")
		(10 "In4.Cu" signal "GND1")
		(12 "In5.Cu" signal "IN1")
		(14 "In6.Cu" signal "GND2")
		(16 "In7.Cu" signal "IN2")
		(18 "In8.Cu" signal "GND3")
		(20 "In9.Cu" signal "IN3")
		(22 "In10.Cu" signal "GND4")
		(24 "In11.Cu" signal "IN4")
		(26 "In12.Cu" signal "GND5")
		(28 "In13.Cu" signal "IN5")
		(30 "In14.Cu" signal "GND6")
		(32 "In15.Cu" signal "IN6")
		(34 "In16.Cu" signal "GND7")
		(2 "B.Cu" signal "BOTTOM")
		(9 "F.Adhes" user "F.Adhesive")
		(11 "B.Adhes" user "B.Adhesive")
		(13 "F.Paste" user "Package Geometry/Pastemask Top")
		(15 "B.Paste" user "Package Geometry/Pastemask Bottom")
		(5 "F.SilkS" user "Ref Des/Silkscreen Top")
		(7 "B.SilkS" user "Ref Des/Silkscreen Bottom")
		(1 "F.Mask" user "Board Geometry/Soldermask Top")
		(3 "B.Mask" user "Board Geometry/Soldermask Bottom")
		(17 "Dwgs.User" user "User.Drawings")
		(19 "Cmts.User" user "User.Comments")
		(21 "Eco1.User" user "User.Eco1")
		(23 "Eco2.User" user "User.Eco2")
		(25 "Edge.Cuts" user "Board Geometry/Outline")
		(27 "Margin" user)
		(31 "F.CrtYd" user "Package Geometry/Place Bound Top")
		(29 "B.CrtYd" user "Package Geometry/Place Bound Bottom")
		(35 "F.Fab" user "Ref Des/Assembly Top")
		(33 "B.Fab" user "Ref Des/Assembly Bottom")
	)
	(footprint ""
		(layer "F.Cu")
		(at 89.649808 -320.900044)
		(property "Reference" "H88"
			(at -6.698234 -7.580884 0)
			(unlocked yes)
			(layer "F.SilkS")
			(effects
				(font
					(size 0.7874 0.5842)
					(thickness 0.1524)
				)
				(justify left)
			)
		)
		(property "Value" ""
			(at 0 0 0)
			(layer "F.Fab")
			(effects
				(font
					(size 1.27 1.27)
				)
			)
		)
		(duplicate_pad_numbers_are_jumpers no)
		(fp_arc
			(start -7.997444 -0.2032)
			(mid 0.10159 -7.999338)
			(end 7.999984 0)
			(stroke
				(width 0.1524)
				(type default)
			)
			(layer "F.SilkS")
		)
		(fp_arc
			(start 7.999984 0)
			(mid 3.104805 7.372968)
			(end -5.590032 5.722874)
			(stroke
				(width 0.1524)
				(type default)
			)
			(layer "F.SilkS")
		)
		(fp_arc
			(start -7.9756 0.623062)
			(mid -7.040405 -3.7988)
			(end -3.858006 -7.008114)
			(stroke
				(width 0.1524)
				(type default)
			)
			(layer "B.SilkS")
		)
		(fp_arc
			(start -1.80848 -7.79272)
			(mid 0.009393 -7.999763)
			(end 1.826768 -7.788402)
			(stroke
				(width 0.1524)
				(type default)
			)
			(layer "B.SilkS")
		)
		(fp_arc
			(start 4.00304 -6.926326)
			(mid 6.929054 -3.998416)
			(end 7.999984 0)
			(stroke
				(width 0.1524)
				(type default)
			)
			(layer "B.SilkS")
		)
		(fp_arc
			(start 7.999984 0)
			(mid 3.342574 7.268164)
			(end -5.206746 6.073648)
			(stroke
				(width 0.1524)
				(type default)
			)
			(layer "B.SilkS")
		)
		(fp_circle
			(center 0 0)
			(end 7.999984 0)
			(stroke
				(width 0.1)
				(type default)
			)
			(fill no)
			(layer "B.Fab")
		)
		(fp_circle
			(center 0 0)
			(end 7.999984 0)
			(stroke
				(width 0.1)
				(type default)
			)
			(fill no)
			(layer "F.Fab")
		)
		(pad "" np_thru_hole circle
			(at 0 0)
			(size 4.5212 4.5212)
			(drill 4.5212)
			(layers "*.Cu" "*.Mask")
			(clearance 0.381)
			(thermal_gap 0.381)
		)
		(pad "2" thru_hole circle
			(at 3.6322 0)
			(size 0.762 0.762)
			(drill 0.5588)
			(layers "*.Cu" "*.Mask")
			(remove_unused_layers no)
			(net "GND")
			(clearance 0.1524)
			(thermal_gap 0.1524)
		)
		(pad "3" thru_hole circle
			(at 2.568448 -2.568448)
			(size 0.762 0.762)
			(drill 0.5588)
			(layers "*.Cu" "*.Mask")
			(remove_unused_layers no)
			(net "GND")
			(clearance 0.1524)
			(thermal_gap 0.1524)
		)
		(pad "4" thru_hole circle
			(at 0 -3.6322)
			(size 0.762 0.762)
			(drill 0.5588)
			(layers "*.Cu" "*.Mask")
			(remove_unused_layers no)
			(net "GND")
			(clearance 0.1524)
			(thermal_gap 0.1524)
		)
		(pad "5" thru_hole circle
			(at -2.568448 -2.568448)
			(size 0.762 0.762)
			(drill 0.5588)
			(layers "*.Cu" "*.Mask")
			(remove_unused_layers no)
			(net "GND")
			(clearance 0.1524)
			(thermal_gap 0.1524)
		)
		(pad "6" thru_hole circle
			(at -3.6322 0)
			(size 0.762 0.762)
			(drill 0.5588)
			(layers "*.Cu" "*.Mask")
			(remove_unused_layers no)
			(net "GND")
			(clearance 0.1524)
			(thermal_gap 0.1524)
		)
		(pad "7" thru_hole circle
			(at -2.568448 2.568448)
			(size 0.762 0.762)
			(drill 0.5588)
			(layers "*.Cu" "*.Mask")
			(remove_unused_layers no)
			(net "GND")
			(clearance 0.1524)
			(thermal_gap 0.1524)
		)
		(pad "8" thru_hole circle
			(at 0 3.6322)
			(size 0.762 0.762)
			(drill 0.5588)
			(layers "*.Cu" "*.Mask")
			(remove_unused_layers no)
			(net "GND")
			(clearance 0.1524)
			(thermal_gap 0.1524)
		)
		(pad "9" thru_hole circle
			(at 2.568448 2.568448)
			(size 0.762 0.762)
			(drill 0.5588)
			(layers "*.Cu" "*.Mask")
			(remove_unused_layers no)
			(net "GND")
			(clearance 0.1524)
			(thermal_gap 0.1524)
		)
		(zone
			(layer "F.Cu")
			(hatch none 0.5)
			(connect_pads
				(clearance 0)
			)
			(min_thickness 0.25)
			(keepout
				(tracks not_allowed)
				(vias allowed)
				(pads allowed)
				(copperpour not_allowed)
				(footprints allowed)
			)
			(placement
				(enabled no)
				(sheetname "")
			)
			(fill
				(thermal_gap 0.5)
				(thermal_bridge_width 0.5)
				(island_removal_mode 0)
			)
			(polygon
				(pts
					(arc
						(start 89.649808 -312.90006)
						(mid 81.649824 -320.900044)
						(end 89.649808 -328.900028)
					)
					(arc
						(start 89.649808 -325.649844)
						(mid 84.900008 -320.900044)
						(end 89.649808 -316.150244)
					)
				)
			)
		)
		(zone
			(layer "F.Cu")
			(hatch none 0.5)
			(connect_pads
				(clearance 0)
			)
			(min_thickness 0.25)
			(keepout
				(tracks not_allowed)
				(vias allowed)
				(pads allowed)
				(copperpour not_allowed)
				(footprints allowed)
			)
			(placement
				(enabled no)
				(sheetname "")
			)
			(fill
				(thermal_gap 0.5)
				(thermal_bridge_width 0.5)
				(island_removal_mode 0)
			)
			(polygon
				(pts
					(arc
						(start 89.649808 -312.90006)
						(mid 97.649792 -320.900044)
						(end 89.649808 -328.900028)
					)
					(arc
						(start 89.649808 -325.649844)
						(mid 94.399608 -320.900044)
						(end 89.649808 -316.150244)
					)
				)
			)
		)
		(zone
			(layers "F.Cu" "B.Cu" "In1.Cu" "In2.Cu" "In3.Cu" "In4.Cu" "In5.Cu" "In6.Cu"
				"In7.Cu" "In8.Cu" "In9.Cu" "In10.Cu" "In11.Cu" "In12.Cu" "In13.Cu" "In14.Cu"
				"In15.Cu" "In16.Cu"
			)
			(hatch none 0.5)
			(connect_pads
				(clearance 0)
			)
			(min_thickness 0.25)
			(keepout
				(tracks not_allowed)
				(vias allowed)
				(pads allowed)
				(copperpour not_allowed)
				(footprints allowed)
			)
			(placement
				(enabled no)
				(sheetname "")
			)
			(fill
				(thermal_gap 0.5)
				(thermal_bridge_width 0.5)
				(island_removal_mode 0)
			)
			(polygon
				(pts
					(arc
						(start 92.415868 -320.900044)
						(mid 86.883748 -320.900044)
						(end 92.415868 -320.900044)
					)
				)
			)
		)
		(zone
			(layer "B.Cu")
			(hatch none 0.5)
			(connect_pads
				(clearance 0)
			)
			(min_thickness 0.25)
			(keepout
				(tracks not_allowed)
				(vias allowed)
				(pads allowed)
				(copperpour not_allowed)
				(footprints allowed)
			)
			(placement
				(enabled no)
				(sheetname "")
			)
			(fill
				(thermal_gap 0.5)
				(thermal_bridge_width 0.5)
				(island_removal_mode 0)
			)
			(polygon
				(pts
					(arc
						(start 89.649808 -315.896244)
						(mid 84.646008 -320.900044)
						(end 89.649808 -325.903844)
					)
					(arc
						(start 89.649808 -325.421244)
						(mid 85.128608 -320.900044)
						(end 89.649808 -316.378844)
					)
				)
			)
		)
		(zone
			(layer "B.Cu")
			(hatch none 0.5)
			(connect_pads
				(clearance 0)
			)
			(min_thickness 0.25)
			(keepout
				(tracks not_allowed)
				(vias allowed)
				(pads allowed)
				(copperpour not_allowed)
				(footprints allowed)
			)
			(placement
				(enabled no)
				(sheetname "")
			)
			(fill
				(thermal_gap 0.5)
				(thermal_bridge_width 0.5)
				(island_removal_mode 0)
			)
			(polygon
				(pts
					(arc
						(start 89.649808 -315.896244)
						(mid 94.653608 -320.900044)
						(end 89.649808 -325.903844)
					)
					(arc
						(start 89.649808 -325.421244)
						(mid 94.171008 -320.900044)
						(end 89.649808 -316.378844)
					)
				)
			)
		)
	)
	(footprint ""
		(layer "F.Cu")
		(at 338.074 -143.891 180)
		(property "Reference" "R4835"
			(at 0 0 180)
			(layer "F.SilkS")
			(hide yes)
			(effects
				(font
					(size 1.27 1.27)
				)
			)
		)
		(property "Value" ""
			(at 0 0 180)
			(layer "F.Fab")
			(effects
				(font
					(size 1.27 1.27)
				)
			)
		)
		(duplicate_pad_numbers_are_jumpers no)
		(fp_line
			(start 0.7874 0.4064)
			(end -0.7874 0.4064)
			(stroke
				(width 0.1524)
				(type default)
			)
			(layer "F.SilkS")
		)
		(fp_line
			(start 0.7874 -0.4064)
			(end 0.7874 0.4064)
			(stroke
				(width 0.1524)
				(type default)
			)
			(layer "F.SilkS")
		)
		(fp_line
			(start -0.7874 0.4064)
			(end -0.7874 -0.4064)
			(stroke
				(width 0.1524)
				(type default)
			)
			(layer "F.SilkS")
		)
		(fp_line
			(start -0.7874 -0.4064)
			(end 0.7874 -0.4064)
			(stroke
				(width 0.1524)
				(type default)
			)
			(layer "F.SilkS")
		)
		(fp_line
			(start 0.67945 0.3048)
			(end 0.120396 0.3048)
			(stroke
				(width 0.1)
				(type default)
			)
			(layer "F.Fab")
		)
		(fp_line
			(start 0.67945 -0.3048)
			(end 0.67945 0.3048)
			(stroke
				(width 0.1)
				(type default)
			)
			(layer "F.Fab")
		)
		(fp_line
			(start 0.12065 -0.2794)
			(end 0.12065 -0.3048)
			(stroke
				(width 0.1)
				(type default)
			)
			(layer "F.Fab")
		)
		(fp_line
			(start 0.12065 -0.3048)
			(end 0.67945 -0.3048)
			(stroke
				(width 0.1)
				(type default)
			)
			(layer "F.Fab")
		)
		(fp_line
			(start 0.120396 0.3048)
			(end 0.120396 0.2794)
			(stroke
				(width 0.1)
				(type default)
			)
			(layer "F.Fab")
		)
		(fp_line
			(start 0.120396 0.2794)
			(end -0.12065 0.2794)
			(stroke
				(width 0.1)
				(type default)
			)
			(layer "F.Fab")
		)
		(fp_line
			(start -0.12065 0.3048)
			(end -0.67945 0.3048)
			(stroke
				(width 0.1)
				(type default)
			)
			(layer "F.Fab")
		)
		(fp_line
			(start -0.12065 0.2794)
			(end -0.12065 0.3048)
			(stroke
				(width 0.1)
				(type default)
			)
			(layer "F.Fab")
		)
		(fp_line
			(start -0.12065 -0.2794)
			(end 0.12065 -0.2794)
			(stroke
				(width 0.1)
				(type default)
			)
			(layer "F.Fab")
		)
		(fp_line
			(start -0.12065 -0.305054)
			(end -0.12065 -0.2794)
			(stroke
				(width 0.1)
				(type default)
			)
			(layer "F.Fab")
		)
		(fp_line
			(start -0.67945 0.3048)
			(end -0.67945 -0.305054)
			(stroke
				(width 0.1)
				(type default)
			)
			(layer "F.Fab")
		)
		(fp_line
			(start -0.67945 -0.305054)
			(end -0.12065 -0.305054)
			(stroke
				(width 0.1)
				(type default)
			)
			(layer "F.Fab")
		)
		(pad "1" smd circle
			(at -0.40005 0 180)
			(size 0 0)
			(layers "F.Cu" "F.Mask" "F.Paste")
			(net "PRSNT_SSD15_FPGA_PCA9555_N")
		)
		(pad "2" smd circle
			(at 0.40005 0 180)
			(size 0 0)
			(layers "F.Cu" "F.Mask" "F.Paste")
			(net "PRSNT_SSD15_FPGA_R_N")
		)
	)
	(footprint ""
		(layer "F.Cu")
		(at 446.096136 -47.20082 90)
		(property "Reference" "C407"
			(at 0 0 90)
			(layer "F.SilkS")
			(hide yes)
			(effects
				(font
					(size 1.27 1.27)
				)
			)
		)
		(property "Value" ""
			(at 0 0 90)
			(layer "F.Fab")
			(effects
				(font
					(size 1.27 1.27)
				)
			)
		)
		(duplicate_pad_numbers_are_jumpers no)
		(fp_line
			(start 0.7874 -0.4064)
			(end 0.7874 0.4064)
			(stroke
				(width 0.1524)
				(type default)
			)
			(layer "F.SilkS")
		)
		(fp_line
			(start -0.7874 -0.4064)
			(end 0.7874 -0.4064)
			(stroke
				(width 0.1524)
				(type default)
			)
			(layer "F.SilkS")
		)
		(fp_line
			(start 0.7874 0.4064)
			(end -0.7874 0.4064)
			(stroke
				(width 0.1524)
				(type default)
			)
			(layer "F.SilkS")
		)
		(fp_line
			(start -0.7874 0.4064)
			(end -0.7874 -0.4064)
			(stroke
				(width 0.1524)
				(type default)
			)
			(layer "F.SilkS")
		)
		(fp_line
			(start -0.12065 -0.305054)
			(end -0.12065 -0.2794)
			(stroke
				(width 0.1)
				(type default)
			)
			(layer "F.Fab")
		)
		(fp_line
			(start -0.67945 -0.305054)
			(end -0.12065 -0.305054)
			(stroke
				(width 0.1)
				(type default)
			)
			(layer "F.Fab")
		)
		(fp_line
			(start 0.67945 -0.3048)
			(end 0.67945 0.3048)
			(stroke
				(width 0.1)
				(type default)
			)
			(layer "F.Fab")
		)
		(fp_line
			(start 0.12065 -0.3048)
			(end 0.67945 -0.3048)
			(stroke
				(width 0.1)
				(type default)
			)
			(layer "F.Fab")
		)
		(fp_line
			(start 0.12065 -0.2794)
			(end 0.12065 -0.3048)
			(stroke
				(width 0.1)
				(type default)
			)
			(layer "F.Fab")
		)
		(fp_line
			(start -0.12065 -0.2794)
			(end 0.12065 -0.2794)
			(stroke
				(width 0.1)
				(type default)
			)
			(layer "F.Fab")
		)
		(fp_line
			(start 0.120396 0.2794)
			(end -0.12065 0.2794)
			(stroke
				(width 0.1)
				(type default)
			)
			(layer "F.Fab")
		)
		(fp_line
			(start -0.12065 0.2794)
			(end -0.12065 0.3048)
			(stroke
				(width 0.1)
				(type default)
			)
			(layer "F.Fab")
		)
		(fp_line
			(start 0.67945 0.3048)
			(end 0.120396 0.3048)
			(stroke
				(width 0.1)
				(type default)
			)
			(layer "F.Fab")
		)
		(fp_line
			(start 0.120396 0.3048)
			(end 0.120396 0.2794)
			(stroke
				(width 0.1)
				(type default)
			)
			(layer "F.Fab")
		)
		(fp_line
			(start -0.12065 0.3048)
			(end -0.67945 0.3048)
			(stroke
				(width 0.1)
				(type default)
			)
			(layer "F.Fab")
		)
		(fp_line
			(start -0.67945 0.3048)
			(end -0.67945 -0.305054)
			(stroke
				(width 0.1)
				(type default)
			)
			(layer "F.Fab")
		)
		(pad "1" smd circle
			(at -0.40005 0 90)
			(size 0 0)
			(layers "F.Cu" "F.Mask" "F.Paste")
			(net "P12V_SSD15_R")
		)
		(pad "2" smd circle
			(at 0.40005 0 90)
			(size 0 0)
			(layers "F.Cu" "F.Mask" "F.Paste")
			(net "GND")
		)
	)
	(footprint ""
		(layer "F.Cu")
		(at 153.104596 -140.85697 180)
		(property "Reference" "R135"
			(at 0 0 180)
			(layer "F.SilkS")
			(hide yes)
			(effects
				(font
					(size 1.27 1.27)
				)
			)
		)
		(property "Value" ""
			(at 0 0 180)
			(layer "F.Fab")
			(effects
				(font
					(size 1.27 1.27)
				)
			)
		)
		(duplicate_pad_numbers_are_jumpers no)
		(fp_line
			(start 0.7874 0.4064)
			(end -0.7874 0.4064)
			(stroke
				(width 0.1524)
				(type default)
			)
			(layer "F.SilkS")
		)
		(fp_line
			(start 0.7874 -0.4064)
			(end 0.7874 0.4064)
			(stroke
				(width 0.1524)
				(type default)
			)
			(layer "F.SilkS")
		)
		(fp_line
			(start -0.7874 0.4064)
			(end -0.7874 -0.4064)
			(stroke
				(width 0.1524)
				(type default)
			)
			(layer "F.SilkS")
		)
		(fp_line
			(start -0.7874 -0.4064)
			(end 0.7874 -0.4064)
			(stroke
				(width 0.1524)
				(type default)
			)
			(layer "F.SilkS")
		)
		(fp_line
			(start 0.67945 0.3048)
			(end 0.120396 0.3048)
			(stroke
				(width 0.1)
				(type default)
			)
			(layer "F.Fab")
		)
		(fp_line
			(start 0.67945 -0.3048)
			(end 0.67945 0.3048)
			(stroke
				(width 0.1)
				(type default)
			)
			(layer "F.Fab")
		)
		(fp_line
			(start 0.12065 -0.2794)
			(end 0.12065 -0.3048)
			(stroke
				(width 0.1)
				(type default)
			)
			(layer "F.Fab")
		)
		(fp_line
			(start 0.12065 -0.3048)
			(end 0.67945 -0.3048)
			(stroke
				(width 0.1)
				(type default)
			)
			(layer "F.Fab")
		)
		(fp_line
			(start 0.120396 0.3048)
			(end 0.120396 0.2794)
			(stroke
				(width 0.1)
				(type default)
			)
			(layer "F.Fab")
		)
		(fp_line
			(start 0.120396 0.2794)
			(end -0.12065 0.2794)
			(stroke
				(width 0.1)
				(type default)
			)
			(layer "F.Fab")
		)
		(fp_line
			(start -0.12065 0.3048)
			(end -0.67945 0.3048)
			(stroke
				(width 0.1)
				(type default)
			)
			(layer "F.Fab")
		)
		(fp_line
			(start -0.12065 0.2794)
			(end -0.12065 0.3048)
			(stroke
				(width 0.1)
				(type default)
			)
			(layer "F.Fab")
		)
		(fp_line
			(start -0.12065 -0.2794)
			(end 0.12065 -0.2794)
			(stroke
				(width 0.1)
				(type default)
			)
			(layer "F.Fab")
		)
		(fp_line
			(start -0.12065 -0.305054)
			(end -0.12065 -0.2794)
			(stroke
				(width 0.1)
				(type default)
			)
			(layer "F.Fab")
		)
		(fp_line
			(start -0.67945 0.3048)
			(end -0.67945 -0.305054)
			(stroke
				(width 0.1)
				(type default)
			)
			(layer "F.Fab")
		)
		(fp_line
			(start -0.67945 -0.305054)
			(end -0.12065 -0.305054)
			(stroke
				(width 0.1)
				(type default)
			)
			(layer "F.Fab")
		)
		(pad "1" smd circle
			(at -0.40005 0 180)
			(size 0 0)
			(layers "F.Cu" "F.Mask" "F.Paste")
			(net "NIC2_BIF2_N")
		)
		(pad "2" smd circle
			(at 0.40005 0 180)
			(size 0 0)
			(layers "F.Cu" "F.Mask" "F.Paste")
			(net "P3V3_AUX")
		)
	)
	(footprint ""
		(layer "F.Cu")
		(at 216.531952 -257.975862 -90)
		(property "Reference" "R6496"
			(at 0 0 270)
			(layer "F.SilkS")
			(hide yes)
			(effects
				(font
					(size 1.27 1.27)
				)
			)
		)
		(property "Value" ""
			(at 0 0 270)
			(layer "F.Fab")
			(effects
				(font
					(size 1.27 1.27)
				)
			)
		)
		(duplicate_pad_numbers_are_jumpers no)
		(fp_line
			(start -0.7874 0.4064)
			(end -0.7874 -0.4064)
			(stroke
				(width 0.1524)
				(type default)
			)
			(layer "F.SilkS")
		)
		(fp_line
			(start 0.7874 0.4064)
			(end -0.7874 0.4064)
			(stroke
				(width 0.1524)
				(type default)
			)
			(layer "F.SilkS")
		)
		(fp_line
			(start -0.7874 -0.4064)
			(end 0.7874 -0.4064)
			(stroke
				(width 0.1524)
				(type default)
			)
			(layer "F.SilkS")
		)
		(fp_line
			(start 0.7874 -0.4064)
			(end 0.7874 0.4064)
			(stroke
				(width 0.1524)
				(type default)
			)
			(layer "F.SilkS")
		)
		(fp_line
			(start -0.67945 0.3048)
			(end -0.67945 -0.305054)
			(stroke
				(width 0.1)
				(type default)
			)
			(layer "F.Fab")
		)
		(fp_line
			(start -0.12065 0.3048)
			(end -0.67945 0.3048)
			(stroke
				(width 0.1)
				(type default)
			)
			(layer "F.Fab")
		)
		(fp_line
			(start 0.120396 0.3048)
			(end 0.120396 0.2794)
			(stroke
				(width 0.1)
				(type default)
			)
			(layer "F.Fab")
		)
		(fp_line
			(start 0.67945 0.3048)
			(end 0.120396 0.3048)
			(stroke
				(width 0.1)
				(type default)
			)
			(layer "F.Fab")
		)
		(fp_line
			(start -0.12065 0.2794)
			(end -0.12065 0.3048)
			(stroke
				(width 0.1)
				(type default)
			)
			(layer "F.Fab")
		)
		(fp_line
			(start 0.120396 0.2794)
			(end -0.12065 0.2794)
			(stroke
				(width 0.1)
				(type default)
			)
			(layer "F.Fab")
		)
		(fp_line
			(start -0.12065 -0.2794)
			(end 0.12065 -0.2794)
			(stroke
				(width 0.1)
				(type default)
			)
			(layer "F.Fab")
		)
		(fp_line
			(start 0.12065 -0.2794)
			(end 0.12065 -0.3048)
			(stroke
				(width 0.1)
				(type default)
			)
			(layer "F.Fab")
		)
		(fp_line
			(start 0.12065 -0.3048)
			(end 0.67945 -0.3048)
			(stroke
				(width 0.1)
				(type default)
			)
			(layer "F.Fab")
		)
		(fp_line
			(start 0.67945 -0.3048)
			(end 0.67945 0.3048)
			(stroke
				(width 0.1)
				(type default)
			)
			(layer "F.Fab")
		)
		(fp_line
			(start -0.67945 -0.305054)
			(end -0.12065 -0.305054)
			(stroke
				(width 0.1)
				(type default)
			)
			(layer "F.Fab")
		)
		(fp_line
			(start -0.12065 -0.305054)
			(end -0.12065 -0.2794)
			(stroke
				(width 0.1)
				(type default)
			)
			(layer "F.Fab")
		)
		(pad "1" smd circle
			(at -0.40005 0 270)
			(size 0 0)
			(layers "F.Cu" "F.Mask" "F.Paste")
			(net "P1V25_SERDES_VDDPLL_PEX1")
		)
		(pad "2" smd circle
			(at 0.40005 0 270)
			(size 0 0)
			(layers "F.Cu" "F.Mask" "F.Paste")
			(net "P1V25_SERDES_VDDPLL_PEX1_C5")
		)
	)
)
